(kicad_pcb
	(version 20240108)
	(generator "pcbnew")
	(generator_version "8.0")
	(general
		(thickness 1.6)
		(legacy_teardrops no)
	)
	(paper "A4")
	(title_block
		(title "Jetson Orin Baseboard OCuLink Expansion")
		(date "2025-03-18")
		(rev "1.1.0")
		(company "Antmicro Ltd")
		(comment 1 "www.antmicro.com")
		(comment 9 "footprints 99-103 of 119")
	)
	(layers
		(0 "F.Cu" signal)
		(1 "In1.Cu" signal)
		(2 "In2.Cu" signal)
		(31 "B.Cu" signal)
		(32 "B.Adhes" user "B.Adhesive")
		(33 "F.Adhes" user "F.Adhesive")
		(34 "B.Paste" user)
		(35 "F.Paste" user)
		(36 "B.SilkS" user "B.Silkscreen")
		(37 "F.SilkS" user "F.Silkscreen")
		(38 "B.Mask" user)
		(39 "F.Mask" user)
		(40 "Dwgs.User" user "User.Drawings")
		(41 "Cmts.User" user "User.Comments")
		(42 "Eco1.User" user "User.Eco1")
		(43 "Eco2.User" user "User.Eco2")
		(44 "Edge.Cuts" user)
		(45 "Margin" user)
		(46 "B.CrtYd" user "B.Courtyard")
		(47 "F.CrtYd" user "F.Courtyard")
		(48 "B.Fab" user)
		(49 "F.Fab" user)
	)
	(footprint "antmicro-footprints:R_0402_1005Metric"
		(layer "B.Cu")
		(at 113.73 130.28 90)
		(descr "Resistor SMD 0402")
		(tags "resistor SMD 0402")
		(property "Reference" "R44"
			(at -2.96 -0.39 90)
			(layer "B.SilkS")
			(effects
				(font
					(size 0.7 0.7)
					(thickness 0.15)
				)
				(justify right top mirror)
			)
		)
		(property "Value" "R_0R_0402"
			(at -1.011843 -1.772047 90)
			(layer "B.Fab")
			(effects
				(font
					(size 0.7 0.7)
					(thickness 0.15)
				)
				(justify right top mirror)
			)
		)
		(property "Footprint" "antmicro-footprints:R_0402_1005Metric"
			(at 0 0 90)
			(layer "B.Fab")
			(hide yes)
			(effects
				(font
					(size 1.27 1.27)
					(thickness 0.15)
				)
				(justify mirror)
			)
		)
		(property "Datasheet" "https://industrial.panasonic.com/cdbs/www-data/pdf/RDA0000/AOA0000C301.pdf"
			(at 0 0 90)
			(layer "B.Fab")
			(hide yes)
			(effects
				(font
					(size 1.27 1.27)
					(thickness 0.15)
				)
				(justify mirror)
			)
		)
		(property "Description" "SMD Chip Resistor, Jumper, 0 ohm, 100 mW, 0402 [1005 Metric], Thick Film, General Purpose"
			(at 0 0 90)
			(layer "B.Fab")
			(hide yes)
			(effects
				(font
					(size 1.27 1.27)
					(thickness 0.15)
				)
				(justify mirror)
			)
		)
		(property "MPN" "ERJ2GE0R00X"
			(at 0 0 -90)
			(unlocked yes)
			(layer "B.Fab")
			(hide yes)
			(effects
				(font
					(size 1 1)
					(thickness 0.15)
				)
				(justify mirror)
			)
		)
		(property "Manufacturer" "Panasonic"
			(at 0 0 -90)
			(unlocked yes)
			(layer "B.Fab")
			(hide yes)
			(effects
				(font
					(size 1 1)
					(thickness 0.15)
				)
				(justify mirror)
			)
		)
		(property "License" "Apache-2.0"
			(at 0 0 -90)
			(unlocked yes)
			(layer "B.Fab")
			(hide yes)
			(effects
				(font
					(size 1 1)
					(thickness 0.15)
				)
				(justify mirror)
			)
		)
		(property "Author" "Antmicro"
			(at 0 0 -90)
			(unlocked yes)
			(layer "B.Fab")
			(hide yes)
			(effects
				(font
					(size 1 1)
					(thickness 0.15)
				)
				(justify mirror)
			)
		)
		(property "Val" "0R"
			(at 0 0 -90)
			(unlocked yes)
			(layer "B.Fab")
			(hide yes)
			(effects
				(font
					(size 1 1)
					(thickness 0.15)
				)
				(justify mirror)
			)
		)
		(property "Tolerance" ""
			(at 0 0 -90)
			(unlocked yes)
			(layer "B.Fab")
			(hide yes)
			(effects
				(font
					(size 1 1)
					(thickness 0.15)
				)
				(justify mirror)
			)
		)
		(property "Current" "1A"
			(at 0 0 -90)
			(unlocked yes)
			(layer "B.Fab")
			(hide yes)
			(effects
				(font
					(size 1 1)
					(thickness 0.15)
				)
				(justify mirror)
			)
		)
		(property "Public" "False"
			(at 0 0 -90)
			(unlocked yes)
			(layer "B.Fab")
			(hide yes)
			(effects
				(font
					(size 1 1)
					(thickness 0.15)
				)
				(justify mirror)
			)
		)
		(sheetname "Root")
		(sheetfile "jetson-orin-baseboard-oculink-expansion.kicad_sch")
		(attr smd dnp)
		(fp_rect
			(start -0.925 0.47)
			(end 0.925 -0.47)
			(stroke
				(width 0.05)
				(type default)
			)
			(fill none)
			(layer "B.CrtYd")
		)
		(fp_rect
			(start -0.5 0.25)
			(end 0.5 -0.25)
			(stroke
				(width 0.15)
				(type solid)
			)
			(fill none)
			(layer "B.Fab")
		)
		(fp_text user "License: Apache-2.0"
			(at -0.95 -5.169 90)
			(layer "B.Fab")
			(hide yes)
			(effects
				(font
					(size 0.7 0.7)
					(thickness 0.15)
				)
				(justify right top mirror)
			)
		)
		(fp_text user "Author: Antmicro"
			(at -0.95 -4.169 90)
			(layer "B.Fab")
			(hide yes)
			(effects
				(font
					(size 0.7 0.7)
					(thickness 0.15)
				)
				(justify right top mirror)
			)
		)
		(fp_text user "${REFERENCE}"
			(at -0.95 -3.168 90)
			(layer "B.Fab")
			(hide yes)
			(effects
				(font
					(size 0.7 0.7)
					(thickness 0.15)
				)
				(justify right top mirror)
			)
		)
		(pad "1" smd roundrect
			(at -0.48 0 90)
			(size 0.59 0.64)
			(layers "B.Cu" "B.Paste" "B.Mask")
			(roundrect_rratio 0.25)
			(net 61 "/I2C_SDA")
			(pintype "passive")
		)
		(pad "2" smd roundrect
			(at 0.48 0 90)
			(size 0.59 0.64)
			(layers "B.Cu" "B.Paste" "B.Mask")
			(roundrect_rratio 0.25)
			(net 107 "Net-(U3-SDA)")
			(pintype "passive")
		)
	)
	(footprint "antmicro-footprints:C_0402_1005Metric"
		(layer "B.Cu")
		(at 126.505 116.687251 -90)
		(descr "Capacitor SMD 0402")
		(tags "capacitor SMD 0402")
		(property "Reference" "C10"
			(at 1.782749 -0.435 90)
			(layer "B.SilkS")
			(effects
				(font
					(size 0.7 0.7)
					(thickness 0.15)
				)
				(justify left bottom mirror)
			)
		)
		(property "Value" "C_100n_0402"
			(at -1.022927 -2.155213 90)
			(layer "B.Fab")
			(effects
				(font
					(size 0.7 0.7)
					(thickness 0.15)
				)
				(justify left bottom mirror)
			)
		)
		(property "Footprint" "antmicro-footprints:C_0402_1005Metric"
			(at 0 0 90)
			(layer "B.Fab")
			(hide yes)
			(effects
				(font
					(size 1.27 1.27)
					(thickness 0.15)
				)
				(justify mirror)
			)
		)
		(property "Datasheet" "https://www.murata.com/products/productdetail?partno=GRM155R61H104KE14%23"
			(at 0 0 90)
			(layer "B.Fab")
			(hide yes)
			(effects
				(font
					(size 1.27 1.27)
					(thickness 0.15)
				)
				(justify mirror)
			)
		)
		(property "Description" "SMD Multilayer Ceramic Capacitor, 0.1 µF, 50 V, 0402 [1005 Metric], ± 10%, X5R, GRM Series"
			(at 0 0 90)
			(layer "B.Fab")
			(hide yes)
			(effects
				(font
					(size 1.27 1.27)
					(thickness 0.15)
				)
				(justify mirror)
			)
		)
		(property "MPN" "GRM155R61H104KE14D"
			(at 0 0 90)
			(unlocked yes)
			(layer "B.Fab")
			(hide yes)
			(effects
				(font
					(size 1 1)
					(thickness 0.15)
				)
				(justify mirror)
			)
		)
		(property "Manufacturer" "Murata"
			(at 0 0 90)
			(unlocked yes)
			(layer "B.Fab")
			(hide yes)
			(effects
				(font
					(size 1 1)
					(thickness 0.15)
				)
				(justify mirror)
			)
		)
		(property "License" "Apache-2.0"
			(at 0 0 90)
			(unlocked yes)
			(layer "B.Fab")
			(hide yes)
			(effects
				(font
					(size 1 1)
					(thickness 0.15)
				)
				(justify mirror)
			)
		)
		(property "Author" "Antmicro"
			(at 0 0 90)
			(unlocked yes)
			(layer "B.Fab")
			(hide yes)
			(effects
				(font
					(size 1 1)
					(thickness 0.15)
				)
				(justify mirror)
			)
		)
		(property "Val" "100n"
			(at 0 0 90)
			(unlocked yes)
			(layer "B.Fab")
			(hide yes)
			(effects
				(font
					(size 1 1)
					(thickness 0.15)
				)
				(justify mirror)
			)
		)
		(property "Voltage" "50V"
			(at 0 0 90)
			(unlocked yes)
			(layer "B.Fab")
			(hide yes)
			(effects
				(font
					(size 1 1)
					(thickness 0.15)
				)
				(justify mirror)
			)
		)
		(property "Dielectric" "X5R"
			(at 0 0 90)
			(unlocked yes)
			(layer "B.Fab")
			(hide yes)
			(effects
				(font
					(size 1 1)
					(thickness 0.15)
				)
				(justify mirror)
			)
		)
		(property "Public" "False"
			(at 0 0 90)
			(unlocked yes)
			(layer "B.Fab")
			(hide yes)
			(effects
				(font
					(size 1 1)
					(thickness 0.15)
				)
				(justify mirror)
			)
		)
		(sheetname "Root")
		(sheetfile "jetson-orin-baseboard-oculink-expansion.kicad_sch")
		(attr smd)
		(fp_rect
			(start -0.925 0.47)
			(end 0.925 -0.47)
			(stroke
				(width 0.05)
				(type default)
			)
			(fill none)
			(layer "B.CrtYd")
		)
		(fp_line
			(start -0.494 0.25)
			(end -0.494 -0.248)
			(stroke
				(width 0.15)
				(type solid)
			)
			(layer "B.Fab")
		)
		(fp_line
			(start 0.504 0.25)
			(end -0.494 0.25)
			(stroke
				(width 0.15)
				(type solid)
			)
			(layer "B.Fab")
		)
		(fp_line
			(start -0.494 -0.248)
			(end 0.504 -0.248)
			(stroke
				(width 0.15)
				(type solid)
			)
			(layer "B.Fab")
		)
		(fp_line
			(start 0.504 -0.248)
			(end 0.504 0.25)
			(stroke
				(width 0.15)
				(type solid)
			)
			(layer "B.Fab")
		)
		(fp_text user "Author: Antmicro"
			(at -0.939 -3.399 90)
			(layer "B.Fab")
			(hide yes)
			(effects
				(font
					(size 0.7 0.7)
					(thickness 0.15)
				)
				(justify left bottom mirror)
			)
		)
		(fp_text user "${REFERENCE}"
			(at -0.939 -4.599 90)
			(layer "B.Fab")
			(hide yes)
			(effects
				(font
					(size 0.7 0.7)
					(thickness 0.15)
				)
				(justify left bottom mirror)
			)
		)
		(fp_text user "License: Apache-2.0"
			(at -0.939 -5.799 90)
			(layer "B.Fab")
			(hide yes)
			(effects
				(font
					(size 0.7 0.7)
					(thickness 0.15)
				)
				(justify left bottom mirror)
			)
		)
		(pad "1" smd roundrect
			(at -0.48 0 270)
			(size 0.59 0.64)
			(layers "B.Cu" "B.Paste" "B.Mask")
			(roundrect_rratio 0.25)
			(net 51 "GND")
			(pintype "passive")
		)
		(pad "2" smd roundrect
			(at 0.48 0 270)
			(size 0.59 0.64)
			(layers "B.Cu" "B.Paste" "B.Mask")
			(roundrect_rratio 0.25)
			(net 23 "+3V3")
			(pintype "passive")
		)
	)
	(footprint "antmicro-footprints:R_0402_1005Metric"
		(layer "B.Cu")
		(at 130.5 117.17 180)
		(descr "Resistor SMD 0402")
		(tags "resistor SMD 0402")
		(property "Reference" "R16"
			(at -2.946 -0.451749 0)
			(layer "B.SilkS")
			(effects
				(font
					(size 0.7 0.7)
					(thickness 0.15)
				)
				(justify left bottom mirror)
			)
		)
		(property "Value" "R_10k_0402"
			(at -1.011843 -1.772047 0)
			(layer "B.Fab")
			(effects
				(font
					(size 0.7 0.7)
					(thickness 0.15)
				)
				(justify left bottom mirror)
			)
		)
		(property "Footprint" "antmicro-footprints:R_0402_1005Metric"
			(at 0 0 0)
			(layer "B.Fab")
			(hide yes)
			(effects
				(font
					(size 1.27 1.27)
					(thickness 0.15)
				)
				(justify mirror)
			)
		)
		(property "Datasheet" "https://www.bourns.com/docs/product-datasheets/cr.pdf"
			(at 0 0 0)
			(layer "B.Fab")
			(hide yes)
			(effects
				(font
					(size 1.27 1.27)
					(thickness 0.15)
				)
				(justify mirror)
			)
		)
		(property "Description" "SMD Chip Resistor, 10 kohm, ± 1%, 62.5 mW, 0402 [1005 Metric], Thick Film, General Purpose"
			(at 0 0 0)
			(layer "B.Fab")
			(hide yes)
			(effects
				(font
					(size 1.27 1.27)
					(thickness 0.15)
				)
				(justify mirror)
			)
		)
		(property "MPN" "CR0402-FX-1002GLF"
			(at 0 0 0)
			(unlocked yes)
			(layer "B.Fab")
			(hide yes)
			(effects
				(font
					(size 1 1)
					(thickness 0.15)
				)
				(justify mirror)
			)
		)
		(property "Manufacturer" "Bourns"
			(at 0 0 0)
			(unlocked yes)
			(layer "B.Fab")
			(hide yes)
			(effects
				(font
					(size 1 1)
					(thickness 0.15)
				)
				(justify mirror)
			)
		)
		(property "License" "Apache-2.0"
			(at 0 0 0)
			(unlocked yes)
			(layer "B.Fab")
			(hide yes)
			(effects
				(font
					(size 1 1)
					(thickness 0.15)
				)
				(justify mirror)
			)
		)
		(property "Author" "Antmicro"
			(at 0 0 0)
			(unlocked yes)
			(layer "B.Fab")
			(hide yes)
			(effects
				(font
					(size 1 1)
					(thickness 0.15)
				)
				(justify mirror)
			)
		)
		(property "Val" "10k"
			(at 0 0 0)
			(unlocked yes)
			(layer "B.Fab")
			(hide yes)
			(effects
				(font
					(size 1 1)
					(thickness 0.15)
				)
				(justify mirror)
			)
		)
		(property "Tolerance" "1%"
			(at 0 0 0)
			(unlocked yes)
			(layer "B.Fab")
			(hide yes)
			(effects
				(font
					(size 1 1)
					(thickness 0.15)
				)
				(justify mirror)
			)
		)
		(sheetname "Root")
		(sheetfile "jetson-orin-baseboard-oculink-expansion.kicad_sch")
		(attr smd)
		(fp_rect
			(start -0.925 0.47)
			(end 0.925 -0.47)
			(stroke
				(width 0.05)
				(type default)
			)
			(fill none)
			(layer "B.CrtYd")
		)
		(fp_rect
			(start -0.5 0.25)
			(end 0.5 -0.25)
			(stroke
				(width 0.15)
				(type solid)
			)
			(fill none)
			(layer "B.Fab")
		)
		(fp_text user "${REFERENCE}"
			(at -0.95 -3.168 0)
			(layer "B.Fab")
			(hide yes)
			(effects
				(font
					(size 0.7 0.7)
					(thickness 0.15)
				)
				(justify left bottom mirror)
			)
		)
		(fp_text user "License: Apache-2.0"
			(at -0.95 -5.169 0)
			(layer "B.Fab")
			(hide yes)
			(effects
				(font
					(size 0.7 0.7)
					(thickness 0.15)
				)
				(justify left bottom mirror)
			)
		)
		(fp_text user "Author: Antmicro"
			(at -0.95 -4.169 0)
			(layer "B.Fab")
			(hide yes)
			(effects
				(font
					(size 0.7 0.7)
					(thickness 0.15)
				)
				(justify left bottom mirror)
			)
		)
		(pad "1" smd roundrect
			(at -0.48 0 180)
			(size 0.59 0.64)
			(layers "B.Cu" "B.Paste" "B.Mask")
			(roundrect_rratio 0.25)
			(net 95 "Net-(U2-SDA)")
			(pintype "passive")
		)
		(pad "2" smd roundrect
			(at 0.48 0 180)
			(size 0.59 0.64)
			(layers "B.Cu" "B.Paste" "B.Mask")
			(roundrect_rratio 0.25)
			(net 23 "+3V3")
			(pintype "passive")
		)
	)
	(footprint "antmicro-footprints:TP_SMD_1.5mm"
		(layer "B.Cu")
		(at 126.45 136.3 -90)
		(property "Reference" "TP2"
			(at 0.3395 -2.9365 0)
			(layer "B.SilkS")
			(hide yes)
			(effects
				(font
					(size 0.7 0.7)
					(thickness 0.15)
				)
				(justify left bottom mirror)
			)
		)
		(property "Value" "TP_1.5mm_SMD"
			(at 0 -1.7 90)
			(layer "B.Fab")
			(effects
				(font
					(size 0.7 0.7)
					(thickness 0.15)
				)
				(justify left bottom mirror)
			)
		)
		(property "Footprint" "antmicro-footprints:TP_SMD_1.5mm"
			(at 0 0 90)
			(layer "B.Fab")
			(hide yes)
			(effects
				(font
					(size 1.27 1.27)
					(thickness 0.15)
				)
				(justify mirror)
			)
		)
		(property "Description" "test point, SMT"
			(at 0 0 90)
			(layer "B.Fab")
			(hide yes)
			(effects
				(font
					(size 1.27 1.27)
					(thickness 0.15)
				)
				(justify mirror)
			)
		)
		(property "MPN" ""
			(at 0 0 90)
			(unlocked yes)
			(layer "B.Fab")
			(hide yes)
			(effects
				(font
					(size 1 1)
					(thickness 0.15)
				)
				(justify mirror)
			)
		)
		(property "Manufacturer" ""
			(at 0 0 90)
			(unlocked yes)
			(layer "B.Fab")
			(hide yes)
			(effects
				(font
					(size 1 1)
					(thickness 0.15)
				)
				(justify mirror)
			)
		)
		(property "Author" "Antmicro"
			(at 0 0 90)
			(unlocked yes)
			(layer "B.Fab")
			(hide yes)
			(effects
				(font
					(size 1 1)
					(thickness 0.15)
				)
				(justify mirror)
			)
		)
		(property "License" "Apache-2.0"
			(at 0 0 90)
			(unlocked yes)
			(layer "B.Fab")
			(hide yes)
			(effects
				(font
					(size 1 1)
					(thickness 0.15)
				)
				(justify mirror)
			)
		)
		(sheetname "Root")
		(sheetfile "jetson-orin-baseboard-oculink-expansion.kicad_sch")
		(attr exclude_from_pos_files exclude_from_bom)
		(fp_circle
			(center 0 0)
			(end 0.85 0)
			(stroke
				(width 0.05)
				(type default)
			)
			(fill none)
			(layer "B.CrtYd")
		)
		(fp_text user "License: Apache-2.0"
			(at -0.7 -5.301 90)
			(layer "B.Fab")
			(hide yes)
			(effects
				(font
					(size 0.7 0.7)
					(thickness 0.15)
				)
				(justify left bottom mirror)
			)
		)
		(fp_text user "${REFERENCE}"
			(at -0.7 -2.9 90)
			(layer "B.Fab")
			(hide yes)
			(effects
				(font
					(size 0.7 0.7)
					(thickness 0.15)
				)
				(justify left bottom mirror)
			)
		)
		(fp_text user "Author: Antmicro"
			(at -0.7 -4.101 90)
			(layer "B.Fab")
			(hide yes)
			(effects
				(font
					(size 0.7 0.7)
					(thickness 0.15)
				)
				(justify left bottom mirror)
			)
		)
		(pad "1" smd circle
			(at 0 0)
			(size 1.5 1.5)
			(layers "B.Cu" "B.Mask")
			(net 61 "/I2C_SDA")
			(pinfunction "1")
			(pintype "passive")
		)
	)
	(footprint "antmicro-footprints:R_0402_1005Metric"
		(layer "B.Cu")
		(at 116.475 118.193751)
		(descr "Resistor SMD 0402")
		(tags "resistor SMD 0402")
		(property "Reference" "R15"
			(at -3.251667 -0.383751 0)
			(layer "B.SilkS")
			(effects
				(font
					(size 0.7 0.7)
					(thickness 0.15)
				)
				(justify right top mirror)
			)
		)
		(property "Value" "R_1k_0402"
			(at -1.011843 -1.772047 0)
			(layer "B.Fab")
			(effects
				(font
					(size 0.7 0.7)
					(thickness 0.15)
				)
				(justify right top mirror)
			)
		)
		(property "Footprint" "antmicro-footprints:R_0402_1005Metric"
			(at 0 0 0)
			(layer "B.Fab")
			(hide yes)
			(effects
				(font
					(size 1.27 1.27)
					(thickness 0.15)
				)
				(justify mirror)
			)
		)
		(property "Datasheet" "https://www.bourns.com/docs/product-datasheets/cr.pdf"
			(at 0 0 0)
			(layer "B.Fab")
			(hide yes)
			(effects
				(font
					(size 1.27 1.27)
					(thickness 0.15)
				)
				(justify mirror)
			)
		)
		(property "Description" "SMD Chip Resistor, 1 kohm, ± 1%, 63 mW, 0402 [1005 Metric], Thick Film, General Purpose"
			(at 0 0 0)
			(layer "B.Fab")
			(hide yes)
			(effects
				(font
					(size 1.27 1.27)
					(thickness 0.15)
				)
				(justify mirror)
			)
		)
		(property "MPN" "CR0402-FX-1001GLF"
			(at 0 0 180)
			(unlocked yes)
			(layer "B.Fab")
			(hide yes)
			(effects
				(font
					(size 1 1)
					(thickness 0.15)
				)
				(justify mirror)
			)
		)
		(property "Manufacturer" "Bourns"
			(at 0 0 180)
			(unlocked yes)
			(layer "B.Fab")
			(hide yes)
			(effects
				(font
					(size 1 1)
					(thickness 0.15)
				)
				(justify mirror)
			)
		)
		(property "License" "Apache-2.0"
			(at 0 0 180)
			(unlocked yes)
			(layer "B.Fab")
			(hide yes)
			(effects
				(font
					(size 1 1)
					(thickness 0.15)
				)
				(justify mirror)
			)
		)
		(property "Author" "Antmicro"
			(at 0 0 180)
			(unlocked yes)
			(layer "B.Fab")
			(hide yes)
			(effects
				(font
					(size 1 1)
					(thickness 0.15)
				)
				(justify mirror)
			)
		)
		(property "Val" "1k"
			(at 0 0 180)
			(unlocked yes)
			(layer "B.Fab")
			(hide yes)
			(effects
				(font
					(size 1 1)
					(thickness 0.15)
				)
				(justify mirror)
			)
		)
		(property "Tolerance" "1%"
			(at 0 0 180)
			(unlocked yes)
			(layer "B.Fab")
			(hide yes)
			(effects
				(font
					(size 1 1)
					(thickness 0.15)
				)
				(justify mirror)
			)
		)
		(property "Public" "False"
			(at 0 0 180)
			(unlocked yes)
			(layer "B.Fab")
			(hide yes)
			(effects
				(font
					(size 1 1)
					(thickness 0.15)
				)
				(justify mirror)
			)
		)
		(sheetname "Root")
		(sheetfile "jetson-orin-baseboard-oculink-expansion.kicad_sch")
		(attr smd dnp)
		(fp_rect
			(start -0.925 0.47)
			(end 0.925 -0.47)
			(stroke
				(width 0.05)
				(type default)
			)
			(fill none)
			(layer "B.CrtYd")
		)
		(fp_rect
			(start -0.5 0.25)
			(end 0.5 -0.25)
			(stroke
				(width 0.15)
				(type solid)
			)
			(fill none)
			(layer "B.Fab")
		)
		(fp_text user "License: Apache-2.0"
			(at -0.95 -5.169 0)
			(layer "B.Fab")
			(hide yes)
			(effects
				(font
					(size 0.7 0.7)
					(thickness 0.15)
				)
				(justify right top mirror)
			)
		)
		(fp_text user "${REFERENCE}"
			(at -0.95 -3.168 0)
			(layer "B.Fab")
			(hide yes)
			(effects
				(font
					(size 0.7 0.7)
					(thickness 0.15)
				)
				(justify right top mirror)
			)
		)
		(fp_text user "Author: Antmicro"
			(at -0.95 -4.169 0)
			(layer "B.Fab")
			(hide yes)
			(effects
				(font
					(size 0.7 0.7)
					(thickness 0.15)
				)
				(justify right top mirror)
			)
		)
		(pad "1" smd roundrect
			(at -0.48 0)
			(size 0.59 0.64)
			(layers "B.Cu" "B.Paste" "B.Mask")
			(roundrect_rratio 0.25)
			(net 51 "GND")
			(pintype "passive")
		)
		(pad "2" smd roundrect
			(at 0.48 0)
			(size 0.59 0.64)
			(layers "B.Cu" "B.Paste" "B.Mask")
			(roundrect_rratio 0.25)
			(net 94 "/RX_SW")
			(pintype "passive")
		)
	)
)
